(kicad_pcb
	(version 20241229)
	(generator "pcbnew")
	(generator_version "9.0")
	(general
		(thickness 1.6296)
		(legacy_teardrops no)
	)
	(paper "A3")
	(title_block
		(title "Thunderbolt to 10GbE adapter")
		(date "2026-04-21")
		(rev "1.1.0")
		(company "Antmicro Ltd")
		(comment 1 "www.antmicro.com")
		(comment 9 "footprints 89-91 of 703")
	)
	(layers
		(0 "F.Cu" signal)
		(4 "In1.Cu" signal)
		(6 "In2.Cu" signal)
		(8 "In3.Cu" signal)
		(10 "In4.Cu" signal)
		(12 "In5.Cu" signal)
		(14 "In6.Cu" signal)
		(2 "B.Cu" signal)
		(9 "F.Adhes" user "F.Adhesive")
		(11 "B.Adhes" user "B.Adhesive")
		(13 "F.Paste" user)
		(15 "B.Paste" user)
		(5 "F.SilkS" user "F.Silkscreen")
		(7 "B.SilkS" user "B.Silkscreen")
		(1 "F.Mask" user)
		(3 "B.Mask" user)
		(17 "Dwgs.User" user "User.Drawings")
		(19 "Cmts.User" user "User.Comments")
		(21 "Eco1.User" user "User.Eco1")
		(23 "Eco2.User" user "User.Eco2")
		(25 "Edge.Cuts" user)
		(27 "Margin" user)
		(31 "F.CrtYd" user "F.Courtyard")
		(29 "B.CrtYd" user "B.Courtyard")
		(35 "F.Fab" user)
		(33 "B.Fab" user)
	)
	(footprint "antmicro-footprints:SOIC-8_5.3x5.3x2mm_P1.27mm"
		(layer "F.Cu")
		(at 131.75 77 90)
		(descr "8-Pin SOIC 208-mil")
		(property "Reference" "U19"
			(at 2.6 -3.15 90)
			(layer "F.SilkS")
			(effects
				(font
					(size 0.7 0.7)
					(thickness 0.15)
				)
				(justify left bottom)
			)
		)
		(property "Value" "AT25DF641A-SH"
			(at 0 3.8 90)
			(layer "F.Fab")
			(effects
				(font
					(size 0.7 0.7)
					(thickness 0.15)
				)
				(justify left bottom)
			)
		)
		(property "Datasheet" "https://eu.mouser.com/datasheet/3/1166/1/REN_DS-AT25DF641A-8693G-022022_unsecure_DST_20220220_1.pdf"
			(at 0 0 90)
			(layer "F.Fab")
			(hide yes)
			(effects
				(font
					(size 1.27 1.27)
					(thickness 0.15)
				)
			)
		)
		(property "Description" "NOR Flash 64 Mbit, 3.0V (2.7V to 3.6V), -40C to 85C, SOIC-W 208mil (Tape & Reel), Single, Dual SPI NOR flash"
			(at 0 0 90)
			(layer "F.Fab")
			(hide yes)
			(effects
				(font
					(size 1.27 1.27)
					(thickness 0.15)
				)
			)
		)
		(property "MPN" "AT25DF641A-SH-T "
			(at 0 0 90)
			(unlocked yes)
			(layer "F.Fab")
			(hide yes)
			(effects
				(font
					(size 1 1)
					(thickness 0.15)
				)
			)
		)
		(property "Manufacturer" "Renesas"
			(at 0 0 90)
			(unlocked yes)
			(layer "F.Fab")
			(hide yes)
			(effects
				(font
					(size 1 1)
					(thickness 0.15)
				)
			)
		)
		(property "Author" "Antmicro"
			(at 0 0 90)
			(unlocked yes)
			(layer "F.Fab")
			(hide yes)
			(effects
				(font
					(size 1 1)
					(thickness 0.15)
				)
			)
		)
		(property "License" "Apache-2.0"
			(at 0 0 90)
			(unlocked yes)
			(layer "F.Fab")
			(hide yes)
			(effects
				(font
					(size 1 1)
					(thickness 0.15)
				)
			)
		)
		(sheetname "/X710 flash memory/")
		(sheetfile "flash_x710.kicad_sch")
		(attr smd)
		(fp_line
			(start -2.8 -2.641)
			(end -4.4 -2.641)
			(stroke
				(width 0.15)
				(type solid)
			)
			(layer "F.SilkS")
		)
		(fp_circle
			(center -4.85 -1.905)
			(end -4.8 -1.855)
			(stroke
				(width 0.15)
				(type solid)
			)
			(fill yes)
			(layer "F.SilkS")
		)
		(fp_rect
			(start 4.675 -3)
			(end -4.675 3)
			(stroke
				(width 0.05)
				(type solid)
			)
			(fill no)
			(layer "F.CrtYd")
		)
		(fp_line
			(start 2.64 -2.641)
			(end 2.64 2.64)
			(stroke
				(width 0.15)
				(type solid)
			)
			(layer "F.Fab")
		)
		(fp_line
			(start -2.641 -2.641)
			(end 2.64 -2.641)
			(stroke
				(width 0.15)
				(type solid)
			)
			(layer "F.Fab")
		)
		(fp_line
			(start -2.641 -1.371)
			(end -1.371 -2.641)
			(stroke
				(width 0.15)
				(type solid)
			)
			(layer "F.Fab")
		)
		(fp_line
			(start 2.64 2.64)
			(end -2.641 2.64)
			(stroke
				(width 0.15)
				(type solid)
			)
			(layer "F.Fab")
		)
		(fp_line
			(start -2.641 2.64)
			(end -2.641 -2.641)
			(stroke
				(width 0.15)
				(type solid)
			)
			(layer "F.Fab")
		)
		(fp_text user "${REFERENCE}"
			(at -4.675 4.938 90)
			(layer "F.Fab")
			(effects
				(font
					(size 0.7 0.7)
					(thickness 0.15)
				)
				(justify left bottom)
			)
		)
		(fp_text user "License: Apache-2.0"
			(at -4.675 6.938 90)
			(layer "F.Fab")
			(effects
				(font
					(size 0.7 0.7)
					(thickness 0.15)
				)
				(justify left bottom)
			)
		)
		(fp_text user "Author: Antmicro"
			(at -4.675 5.938 90)
			(layer "F.Fab")
			(effects
				(font
					(size 0.7 0.7)
					(thickness 0.15)
				)
				(justify left bottom)
			)
		)
		(pad "1" smd roundrect
			(at -3.601 -1.905 180)
			(size 0.65 1.65)
			(layers "F.Cu" "F.Mask" "F.Paste")
			(roundrect_rratio 0.25)
			(net 350 "/X710 flash memory/FLASH.~{CE}")
			(pinfunction "~{CS}")
			(pintype "input")
		)
		(pad "2" smd roundrect
			(at -3.601 -0.635 180)
			(size 0.65 1.65)
			(layers "F.Cu" "F.Mask" "F.Paste")
			(roundrect_rratio 0.25)
			(net 351 "/X710 flash memory/FLASH.MISO")
			(pinfunction "SO")
			(pintype "bidirectional")
		)
		(pad "3" smd roundrect
			(at -3.601 0.633 180)
			(size 0.65 1.65)
			(layers "F.Cu" "F.Mask" "F.Paste")
			(roundrect_rratio 0.25)
			(net 388 "/X710 flash memory/~{WP}")
			(pinfunction "~{WP}")
			(pintype "bidirectional")
		)
		(pad "4" smd roundrect
			(at -3.601 1.904 180)
			(size 0.65 1.65)
			(layers "F.Cu" "F.Mask" "F.Paste")
			(roundrect_rratio 0.25)
			(net 23 "GND")
			(pinfunction "GND")
			(pintype "power_in")
		)
		(pad "5" smd roundrect
			(at 3.6 1.904 180)
			(size 0.65 1.65)
			(layers "F.Cu" "F.Mask" "F.Paste")
			(roundrect_rratio 0.25)
			(net 352 "/X710 flash memory/FLASH.MOSI")
			(pinfunction "SI")
			(pintype "bidirectional")
		)
		(pad "6" smd roundrect
			(at 3.6 0.633 180)
			(size 0.65 1.65)
			(layers "F.Cu" "F.Mask" "F.Paste")
			(roundrect_rratio 0.25)
			(net 353 "/X710 flash memory/FLASH.CLK")
			(pinfunction "SCK")
			(pintype "input")
		)
		(pad "7" smd roundrect
			(at 3.6 -0.635 180)
			(size 0.65 1.65)
			(layers "F.Cu" "F.Mask" "F.Paste")
			(roundrect_rratio 0.25)
			(net 387 "/X710 flash memory/~{HOLD}")
			(pinfunction "~{HOLD}")
			(pintype "bidirectional")
		)
		(pad "8" smd roundrect
			(at 3.6 -1.905 180)
			(size 0.65 1.65)
			(layers "F.Cu" "F.Mask" "F.Paste")
			(roundrect_rratio 0.25)
			(net 343 "/X710 flash memory/+3V3_FLASH")
			(pinfunction "VCC")
			(pintype "power_in")
		)
	)
	(footprint "antmicro-footprints:Heatsink_ATS-61500R-C2-R0"
		(layer "F.Cu")
		(at 150.039651 85.998391 180)
		(property "Reference" "H1"
			(at -1.995 -2.5 180)
			(unlocked yes)
			(layer "F.SilkS")
			(hide yes)
			(effects
				(font
					(size 0.7 0.7)
					(thickness 0.15)
				)
				(justify left bottom)
			)
		)
		(property "Value" "Heatsink_ATS-61500R-C2-R0"
			(at 0.003 27.94 180)
			(unlocked yes)
			(layer "F.Fab")
			(effects
				(font
					(size 0.7 0.7)
					(thickness 0.15)
				)
				(justify left bottom)
			)
		)
		(property "Datasheet" "https://www.qats.com/DataSheet/ATS-61500-Series-C2-R0"
			(at 0 0 180)
			(layer "F.Fab")
			(hide yes)
			(effects
				(font
					(size 1.27 1.27)
					(thickness 0.15)
				)
			)
		)
		(property "Description" "Heat Sinks fanSINK Assembly with Mounting Hardware"
			(at 0 0 180)
			(layer "F.Fab")
			(hide yes)
			(effects
				(font
					(size 1.27 1.27)
					(thickness 0.15)
				)
			)
		)
		(property "MPN" "ATS-61500R-C2-R0"
			(at 0 0 180)
			(unlocked yes)
			(layer "F.Fab")
			(hide yes)
			(effects
				(font
					(size 1 1)
					(thickness 0.15)
				)
			)
		)
		(property "Manufacturer" "Advanced Thermal Solutions"
			(at 0 0 180)
			(unlocked yes)
			(layer "F.Fab")
			(hide yes)
			(effects
				(font
					(size 1 1)
					(thickness 0.15)
				)
			)
		)
		(property "Author" "Antmicro"
			(at 0 0 180)
			(unlocked yes)
			(layer "F.Fab")
			(hide yes)
			(effects
				(font
					(size 1 1)
					(thickness 0.15)
				)
			)
		)
		(property "License" "Apache-2.0"
			(at 0 0 180)
			(unlocked yes)
			(layer "F.Fab")
			(hide yes)
			(effects
				(font
					(size 1 1)
					(thickness 0.15)
				)
			)
		)
		(property ki_fp_filters "Heatsink_*")
		(sheetname "/")
		(sheetfile "thunderbolt-to-10gbe-adapter.kicad_sch")
		(attr exclude_from_pos_files)
		(fp_circle
			(center 22 22)
			(end 26.22 22)
			(stroke
				(width 0.05)
				(type solid)
			)
			(fill no)
			(layer "F.CrtYd")
		)
		(fp_circle
			(center 22 -22)
			(end 26.22 -22)
			(stroke
				(width 0.05)
				(type solid)
			)
			(fill no)
			(layer "F.CrtYd")
		)
		(fp_circle
			(center -22 22)
			(end -17.78 22)
			(stroke
				(width 0.05)
				(type solid)
			)
			(fill no)
			(layer "F.CrtYd")
		)
		(fp_circle
			(center -22 -22)
			(end -17.78 -22)
			(stroke
				(width 0.05)
				(type solid)
			)
			(fill no)
			(layer "F.CrtYd")
		)
		(fp_text user "${REFERENCE}"
			(at -27.32 30.52 180)
			(layer "F.Fab")
			(effects
				(font
					(size 0.7 0.7)
					(thickness 0.15)
				)
				(justify left bottom)
			)
		)
		(fp_text user "Suggested mounting holes diameter: 3.18 mm"
			(at -9.07 -0.18 180)
			(layer "F.Fab")
			(effects
				(font
					(size 0.7 0.7)
					(thickness 0.15)
				)
				(justify left bottom)
			)
		)
		(fp_text user "License: Apache-2.0"
			(at -27.32 29.32 180)
			(layer "F.Fab")
			(effects
				(font
					(size 0.7 0.7)
					(thickness 0.15)
				)
				(justify left bottom)
			)
		)
		(fp_text user "Author: Antmicro"
			(at -27.32 31.72 180)
			(layer "F.Fab")
			(effects
				(font
					(size 0.7 0.7)
					(thickness 0.15)
				)
				(justify left bottom)
			)
		)
		(zone
			(net 0)
			(net_name "")
			(layers "F.Cu" "B.Cu" "In1.Cu" "In2.Cu" "In3.Cu" "In4.Cu" "In5.Cu" "In6.Cu")
			(hatch edge 0.5)
			(connect_pads
				(clearance 0)
			)
			(min_thickness 0.25)
			(filled_areas_thickness no)
			(keepout
				(tracks not_allowed)
				(vias not_allowed)
				(pads allowed)
				(copperpour not_allowed)
				(footprints allowed)
			)
			(placement
				(enabled no)
				(sheetname "")
			)
			(fill
				(thermal_gap 0.5)
				(thermal_bridge_width 0.5)
			)
			(polygon
				(pts
					(xy 126.019294 108.013761) (xy 126.039651 108.298391) (xy 126.100308 108.577226) (xy 126.20003 108.844591)
					(xy 126.336787 109.095043) (xy 126.507795 109.323482) (xy 126.709573 109.52526) (xy 126.938012 109.696268)
					(xy 127.188464 109.833025) (xy 127.455829 109.932747) (xy 127.734664 109.993404) (xy 128.019294 110.013761)
					(xy 128.303924 109.993404) (xy 128.582759 109.932747) (xy 128.850124 109.833025) (xy 129.100576 109.696268)
					(xy 129.329015 109.52526) (xy 129.530793 109.323482) (xy 129.701801 109.095043) (xy 129.838558 108.844591)
					(xy 129.93828 108.577226) (xy 129.998937 108.298391) (xy 130.019294 108.013761) (xy 129.998937 107.729131)
					(xy 129.93828 107.450296) (xy 129.838558 107.182931) (xy 129.701801 106.932479) (xy 129.530793 106.70404)
					(xy 129.329015 106.502262) (xy 129.100576 106.331254) (xy 128.850124 106.194497) (xy 128.582759 106.094775)
					(xy 128.303924 106.034118) (xy 128.019294 106.013761) (xy 127.734664 106.034118) (xy 127.455829 106.094775)
					(xy 127.188464 106.194497) (xy 126.938012 106.331254) (xy 126.709573 106.502262) (xy 126.507795 106.70404)
					(xy 126.336787 106.932479) (xy 126.20003 107.182931) (xy 126.100308 107.450296) (xy 126.039651 107.729131)
				)
			)
		)
		(zone
			(net 0)
			(net_name "")
			(layers "F.Cu" "B.Cu" "In1.Cu" "In2.Cu" "In3.Cu" "In4.Cu" "In5.Cu" "In6.Cu")
			(hatch edge 0.5)
			(connect_pads
				(clearance 0)
			)
			(min_thickness 0.25)
			(filled_areas_thickness no)
			(keepout
				(tracks not_allowed)
				(vias not_allowed)
				(pads allowed)
				(copperpour not_allowed)
				(footprints allowed)
			)
			(placement
				(enabled no)
				(sheetname "")
			)
			(fill
				(thermal_gap 0.5)
				(thermal_bridge_width 0.5)
			)
			(polygon
				(pts
					(xy 126.022158 64.017377) (xy 126.042515 64.302007) (xy 126.103172 64.580842) (xy 126.202894 64.848207)
					(xy 126.339651 65.098659) (xy 126.510659 65.327098) (xy 126.712437 65.528876) (xy 126.940876 65.699884)
					(xy 127.191328 65.836641) (xy 127.458693 65.936363) (xy 127.737528 65.99702) (xy 128.022158 66.017377)
					(xy 128.306788 65.99702) (xy 128.585623 65.936363) (xy 128.852988 65.836641) (xy 129.10344 65.699884)
					(xy 129.331879 65.528876) (xy 129.533657 65.327098) (xy 129.704665 65.098659) (xy 129.841422 64.848207)
					(xy 129.941144 64.580842) (xy 130.001801 64.302007) (xy 130.022158 64.017377) (xy 130.001801 63.732747)
					(xy 129.941144 63.453912) (xy 129.841422 63.186547) (xy 129.704665 62.936095) (xy 129.533657 62.707656)
					(xy 129.331879 62.505878) (xy 129.10344 62.33487) (xy 128.852988 62.198113) (xy 128.585623 62.098391)
					(xy 128.306788 62.037734) (xy 128.022158 62.017377) (xy 127.737528 62.037734) (xy 127.458693 62.098391)
					(xy 127.191328 62.198113) (xy 126.940876 62.33487) (xy 126.712437 62.505878) (xy 126.510659 62.707656)
					(xy 126.339651 62.936095) (xy 126.202894 63.186547) (xy 126.103172 63.453912) (xy 126.042515 63.732747)
				)
			)
		)
		(zone
			(net 0)
			(net_name "")
			(layers "F.Cu" "B.Cu" "In1.Cu" "In2.Cu" "In3.Cu" "In4.Cu" "In5.Cu" "In6.Cu")
			(hatch edge 0.5)
			(connect_pads
				(clearance 0)
			)
			(min_thickness 0.25)
			(filled_areas_thickness no)
			(keepout
				(tracks not_allowed)
				(vias not_allowed)
				(pads allowed)
				(copperpour not_allowed)
				(footprints allowed)
			)
			(placement
				(enabled no)
				(sheetname "")
			)
			(fill
				(thermal_gap 0.5)
				(thermal_bridge_width 0.5)
			)
			(polygon
				(pts
					(xy 170.039651 64.017377) (xy 170.060008 64.302007) (xy 170.120665 64.580842) (xy 170.220387 64.848207)
					(xy 170.357144 65.098659) (xy 170.528152 65.327098) (xy 170.72993 65.528876) (xy 170.958369 65.699884)
					(xy 171.208821 65.836641) (xy 171.476186 65.936363) (xy 171.755021 65.99702) (xy 172.039651 66.017377)
					(xy 172.324281 65.99702) (xy 172.603116 65.936363) (xy 172.870481 65.836641) (xy 173.120933 65.699884)
					(xy 173.349372 65.528876) (xy 173.55115 65.327098) (xy 173.722158 65.098659) (xy 173.858915 64.848207)
					(xy 173.958637 64.580842) (xy 174.019294 64.302007) (xy 174.039651 64.017377) (xy 174.019294 63.732747)
					(xy 173.958637 63.453912) (xy 173.858915 63.186547) (xy 173.722158 62.936095) (xy 173.55115 62.707656)
					(xy 173.349372 62.505878) (xy 173.120933 62.33487) (xy 172.870481 62.198113) (xy 172.603116 62.098391)
					(xy 172.324281 62.037734) (xy 172.039651 62.017377) (xy 171.755021 62.037734) (xy 171.476186 62.098391)
					(xy 171.208821 62.198113) (xy 170.958369 62.33487) (xy 170.72993 62.505878) (xy 170.528152 62.707656)
					(xy 170.357144 62.936095) (xy 170.220387 63.186547) (xy 170.120665 63.453912) (xy 170.060008 63.732747)
				)
			)
		)
		(zone
			(net 0)
			(net_name "")
			(layers "F.Cu" "B.Cu" "In1.Cu" "In2.Cu" "In3.Cu" "In4.Cu" "In5.Cu" "In6.Cu")
			(hatch edge 0.5)
			(connect_pads
				(clearance 0)
			)
			(min_thickness 0.25)
			(filled_areas_thickness no)
			(keepout
				(tracks not_allowed)
				(vias not_allowed)
				(pads allowed)
				(copperpour not_allowed)
				(footprints allowed)
			)
			(placement
				(enabled no)
				(sheetname "")
			)
			(fill
				(thermal_gap 0.5)
				(thermal_bridge_width 0.5)
			)
			(polygon
				(pts
					(xy 170.039651 107.998391) (xy 170.060008 108.283021) (xy 170.120665 108.561856) (xy 170.220387 108.829221)
					(xy 170.357144 109.079673) (xy 170.528152 109.308112) (xy 170.72993 109.50989) (xy 170.958369 109.680898)
					(xy 171.208821 109.817655) (xy 171.476186 109.917377) (xy 171.755021 109.978034) (xy 172.039651 109.998391)
					(xy 172.324281 109.978034) (xy 172.603116 109.917377) (xy 172.870481 109.817655) (xy 173.120933 109.680898)
					(xy 173.349372 109.50989) (xy 173.55115 109.308112) (xy 173.722158 109.079673) (xy 173.858915 108.829221)
					(xy 173.958637 108.561856) (xy 174.019294 108.283021) (xy 174.039651 107.998391) (xy 174.019294 107.713761)
					(xy 173.958637 107.434926) (xy 173.858915 107.167561) (xy 173.722158 106.917109) (xy 173.55115 106.68867)
					(xy 173.349372 106.486892) (xy 173.120933 106.315884) (xy 172.870481 106.179127) (xy 172.603116 106.079405)
					(xy 172.324281 106.018748) (xy 172.039651 105.998391) (xy 171.755021 106.018748) (xy 171.476186 106.079405)
					(xy 171.208821 106.179127) (xy 170.958369 106.315884) (xy 170.72993 106.486892) (xy 170.528152 106.68867)
					(xy 170.357144 106.917109) (xy 170.220387 107.167561) (xy 170.120665 107.434926) (xy 170.060008 107.713761)
				)
			)
		)
	)
	(footprint "antmicro-footprints:FB_0805_2012Metric"
		(layer "F.Cu")
		(at 129 138.4 180)
		(descr "FERRITE BEAD 0805")
		(tags "FERRITE BEAD 0805")
		(property "Reference" "FB1"
			(at 1.2 1 180)
			(layer "F.SilkS")
			(effects
				(font
					(size 0.7 0.7)
					(thickness 0.15)
				)
				(justify left bottom)
			)
		)
		(property "Value" "FB_30Z_8.5A_Murata-BLM21SN_0805"
			(at 0.001 1.801 180)
			(layer "F.Fab")
			(effects
				(font
					(size 0.7 0.7)
					(thickness 0.15)
				)
				(justify left bottom)
			)
		)
		(property "Datasheet" "https://www.murata.com/en-sg/products/productdata/8796738977822/ENFA0005.pdf?1519270210000"
			(at 0 0 180)
			(layer "F.Fab")
			(hide yes)
			(effects
				(font
					(size 1.27 1.27)
					(thickness 0.15)
				)
			)
		)
		(property "Description" "Ferrite Bead, 0805 [2012 Metric], 30 ohm, 8.5 A, BLM21SN, 0.004 ohm, ± 10ohm, DC power line"
			(at 0 0 180)
			(layer "F.Fab")
			(hide yes)
			(effects
				(font
					(size 1.27 1.27)
					(thickness 0.15)
				)
			)
		)
		(property "MPN" "BLM21SN300SZ1D"
			(at 0 0 180)
			(unlocked yes)
			(layer "F.Fab")
			(hide yes)
			(effects
				(font
					(size 1 1)
					(thickness 0.15)
				)
			)
		)
		(property "Manufacturer" "Murata"
			(at 0 0 180)
			(unlocked yes)
			(layer "F.Fab")
			(hide yes)
			(effects
				(font
					(size 1 1)
					(thickness 0.15)
				)
			)
		)
		(property "License" "Apache-2.0"
			(at 0 0 180)
			(unlocked yes)
			(layer "F.Fab")
			(hide yes)
			(effects
				(font
					(size 1 1)
					(thickness 0.15)
				)
			)
		)
		(property "Author" "Antmicro"
			(at 0 0 180)
			(unlocked yes)
			(layer "F.Fab")
			(hide yes)
			(effects
				(font
					(size 1 1)
					(thickness 0.15)
				)
			)
		)
		(property "Val" "30Z/8.5A"
			(at 0 0 180)
			(unlocked yes)
			(layer "F.Fab")
			(hide yes)
			(effects
				(font
					(size 1 1)
					(thickness 0.15)
				)
			)
		)
		(property "Current" ""
			(at 0 0 180)
			(unlocked yes)
			(layer "F.Fab")
			(hide yes)
			(effects
				(font
					(size 1 1)
					(thickness 0.15)
				)
			)
		)
		(sheetname "/PD and TB DC-DC/")
		(sheetfile "PD_and_TB_DC_DC.kicad_sch")
		(attr smd)
		(fp_line
			(start -0.299 -0.698)
			(end 0.299 -0.698)
			(stroke
				(width 0.15)
				(type solid)
			)
			(layer "F.SilkS")
		)
		(fp_line
			(start -0.319 0.698)
			(end 0.281 0.698)
			(stroke
				(width 0.15)
				(type solid)
			)
			(layer "F.SilkS")
		)
		(fp_rect
			(start 1.95 -0.9)
			(end -1.95 0.9)
			(stroke
				(width 0.05)
				(type default)
			)
			(fill no)
			(layer "F.CrtYd")
		)
		(fp_line
			(start 0.948 -0.676)
			(end 0.948 0.676)
			(stroke
				(width 0.15)
				(type solid)
			)
			(layer "F.Fab")
		)
		(fp_line
			(start -0.948 0.681)
			(end 0.948 0.681)
			(stroke
				(width 0.15)
				(type solid)
			)
			(layer "F.Fab")
		)
		(fp_line
			(start -0.948 -0.676)
			(end -0.948 0.676)
			(stroke
				(width 0.15)
				(type solid)
			)
			(layer "F.Fab")
		)
		(fp_line
			(start -0.948 -0.681)
			(end 0.948 -0.681)
			(stroke
				(width 0.15)
				(type solid)
			)
			(layer "F.Fab")
		)
		(fp_text user "Author: Antmicro"
			(at -1.44 5.001 180)
			(layer "F.Fab")
			(effects
				(font
					(size 0.7 0.7)
					(thickness 0.15)
				)
				(justify left bottom)
			)
		)
		(fp_text user "License: Apache-2.0"
			(at -1.44 6.201 180)
			(layer "F.Fab")
			(effects
				(font
					(size 0.7 0.7)
					(thickness 0.15)
				)
				(justify left bottom)
			)
		)
		(fp_text user "${REFERENCE}"
			(at -1.44 3.801 180)
			(layer "F.Fab")
			(effects
				(font
					(size 0.7 0.7)
					(thickness 0.15)
				)
				(justify left bottom)
			)
		)
		(pad "1" smd roundrect
			(at -1.1 0 180)
			(size 1.2 1.3)
			(layers "F.Cu" "F.Mask" "F.Paste")
			(roundrect_rratio 0.25)
			(net 182 "VBUS")
			(pintype "passive")
		)
		(pad "2" smd roundrect
			(at 1.1 0 180)
			(size 1.2 1.3)
			(layers "F.Cu" "F.Mask" "F.Paste")
			(roundrect_rratio 0.25)
			(net 53 "+5V_USB")
			(pintype "passive")
		)
	)
)
